(kicad_pcb
	(version 20260206)
	(generator "pcbnew")
	(generator_version "10.0")
	(general
		(thickness 1.6)
		(legacy_teardrops no)
	)
	(paper "A4")
	(title_block
		(title "Wiwynn_Tioga_Pass_MB.brd")
		(comment 1 "Tioga Pass / footprints 768-775 of 4770")
	)
	(layers
		(0 "F.Cu" signal "TOP")
		(4 "In1.Cu" signal "L2GND")
		(6 "In2.Cu" signal "L3")
		(8 "In3.Cu" signal "L4GND")
		(10 "In4.Cu" signal "L5")
		(12 "In5.Cu" signal "L6GND")
		(14 "In6.Cu" signal "L7VCC")
		(16 "In7.Cu" signal "L8VCC")
		(18 "In8.Cu" signal "L9GND")
		(20 "In9.Cu" signal "L10")
		(22 "In10.Cu" signal "L11GND")
		(24 "In11.Cu" signal "L12")
		(26 "In12.Cu" signal "L13GND")
		(2 "B.Cu" signal "BOTTOM")
		(9 "F.Adhes" user "F.Adhesive")
		(11 "B.Adhes" user "B.Adhesive")
		(13 "F.Paste" user "Package Geometry/Pastemask Top")
		(15 "B.Paste" user "Package Geometry/Pastemask Bottom")
		(5 "F.SilkS" user "Ref Des/Silkscreen Top")
		(7 "B.SilkS" user "Ref Des/Silkscreen Bottom")
		(1 "F.Mask" user "Board Geometry/Soldermask Top")
		(3 "B.Mask" user "Board Geometry/Soldermask Bottom")
		(17 "Dwgs.User" user "User.Drawings")
		(19 "Cmts.User" user "User.Comments")
		(21 "Eco1.User" user "User.Eco1")
		(23 "Eco2.User" user "User.Eco2")
		(25 "Edge.Cuts" user "Board Geometry/Outline")
		(27 "Margin" user)
		(31 "F.CrtYd" user "Package Geometry/Place Bound Top")
		(29 "B.CrtYd" user "Package Geometry/Place Bound Bottom")
		(35 "F.Fab" user "Ref Des/Assembly Top")
		(33 "B.Fab" user "Ref Des/Assembly Bottom")
	)
	(footprint ""
		(layer "F.Cu")
		(at 396.367 -88.2015)
		(property "Reference" "R2N27"
			(at 0 0 0)
			(layer "F.SilkS")
			(hide yes)
			(effects
				(font
					(size 1.27 1.27)
				)
			)
		)
		(property "Value" ""
			(at 0 0 0)
			(layer "F.Fab")
			(effects
				(font
					(size 1.27 1.27)
				)
			)
		)
		(duplicate_pad_numbers_are_jumpers no)
		(fp_poly
			(pts
				(xy -0.2794 -0.1016) (xy 0.2794 -0.1016) (xy 0.2794 0.9906) (xy -0.2794 0.9906)
			)
			(stroke
				(width 0)
				(type default)
			)
			(fill no)
			(layer "F.CrtYd")
		)
		(fp_line
			(start -0.2794 -0.1016)
			(end -0.2794 0.9906)
			(stroke
				(width 0.1)
				(type default)
			)
			(layer "F.Fab")
		)
		(fp_line
			(start -0.2794 0.9906)
			(end 0.2794 0.9906)
			(stroke
				(width 0.1)
				(type default)
			)
			(layer "F.Fab")
		)
		(fp_line
			(start 0.2794 -0.1016)
			(end -0.2794 -0.1016)
			(stroke
				(width 0.1)
				(type default)
			)
			(layer "F.Fab")
		)
		(fp_line
			(start 0.2794 0.9906)
			(end 0.2794 -0.1016)
			(stroke
				(width 0.1)
				(type default)
			)
			(layer "F.Fab")
		)
		(pad "1" smd rect
			(at 0 0)
			(size 0.508 0.508)
			(layers "F.Cu" "F.Mask" "F.Paste")
			(net "P3V3")
		)
		(pad "2" smd rect
			(at 0 0.889)
			(size 0.508 0.508)
			(layers "F.Cu" "F.Mask" "F.Paste")
			(net "FM_BMC_NMI_N")
		)
		(zone
			(layer "F.Cu")
			(hatch none 0.5)
			(connect_pads
				(clearance 0)
			)
			(min_thickness 0.25)
			(keepout
				(tracks allowed)
				(vias not_allowed)
				(pads allowed)
				(copperpour not_allowed)
				(footprints allowed)
			)
			(placement
				(enabled no)
				(sheetname "")
			)
			(fill
				(thermal_gap 0.5)
				(thermal_bridge_width 0.5)
				(island_removal_mode 0)
			)
			(polygon
				(pts
					(xy 396.113 -87.9475) (xy 396.621 -87.9475) (xy 396.621 -87.5665) (xy 396.113 -87.5665)
				)
			)
		)
		(zone
			(layer "F.Cu")
			(hatch none 0.5)
			(connect_pads
				(clearance 0)
			)
			(min_thickness 0.25)
			(keepout
				(tracks not_allowed)
				(vias allowed)
				(pads allowed)
				(copperpour not_allowed)
				(footprints allowed)
			)
			(placement
				(enabled no)
				(sheetname "")
			)
			(fill
				(thermal_gap 0.5)
				(thermal_bridge_width 0.5)
				(island_removal_mode 0)
			)
			(polygon
				(pts
					(xy 396.113 -87.5665) (xy 396.621 -87.5665) (xy 396.621 -87.9475) (xy 396.113 -87.9475)
				)
			)
		)
	)
	(footprint ""
		(layer "F.Cu")
		(at 342.265 -19.558 180)
		(property "Reference" "R7F24"
			(at 0 0 180)
			(layer "F.SilkS")
			(hide yes)
			(effects
				(font
					(size 1.27 1.27)
				)
			)
		)
		(property "Value" ""
			(at 0 0 180)
			(layer "F.Fab")
			(effects
				(font
					(size 1.27 1.27)
				)
			)
		)
		(duplicate_pad_numbers_are_jumpers no)
		(fp_rect
			(start 0.2794 -0.1016)
			(end -0.2794 0.9906)
			(stroke
				(width 0)
				(type default)
			)
			(fill no)
			(layer "F.CrtYd")
		)
		(fp_line
			(start 0.2794 0.9906)
			(end 0.2794 -0.1016)
			(stroke
				(width 0.1)
				(type default)
			)
			(layer "F.Fab")
		)
		(fp_line
			(start 0.2794 -0.1016)
			(end -0.2794 -0.1016)
			(stroke
				(width 0.1)
				(type default)
			)
			(layer "F.Fab")
		)
		(fp_line
			(start -0.2794 0.9906)
			(end 0.2794 0.9906)
			(stroke
				(width 0.1)
				(type default)
			)
			(layer "F.Fab")
		)
		(fp_line
			(start -0.2794 -0.1016)
			(end -0.2794 0.9906)
			(stroke
				(width 0.1)
				(type default)
			)
			(layer "F.Fab")
		)
		(pad "1" smd rect
			(at 0 0 180)
			(size 0.508 0.508)
			(layers "F.Cu" "F.Mask" "F.Paste")
			(net "PWRGD_PVDDQ_ABC_R")
		)
		(pad "2" smd rect
			(at 0 0.889 180)
			(size 0.508 0.508)
			(layers "F.Cu" "F.Mask" "F.Paste")
			(net "PWRGD_PVDDQ_ABC")
		)
		(zone
			(layer "F.Cu")
			(hatch none 0.5)
			(connect_pads
				(clearance 0)
			)
			(min_thickness 0.25)
			(keepout
				(tracks not_allowed)
				(vias allowed)
				(pads allowed)
				(copperpour not_allowed)
				(footprints allowed)
			)
			(placement
				(enabled no)
				(sheetname "")
			)
			(fill
				(thermal_gap 0.5)
				(thermal_bridge_width 0.5)
				(island_removal_mode 0)
			)
			(polygon
				(pts
					(xy 342.011 -19.812) (xy 342.519 -19.812) (xy 342.519 -20.193) (xy 342.011 -20.193)
				)
			)
		)
		(zone
			(layer "F.Cu")
			(hatch none 0.5)
			(connect_pads
				(clearance 0)
			)
			(min_thickness 0.25)
			(keepout
				(tracks allowed)
				(vias not_allowed)
				(pads allowed)
				(copperpour not_allowed)
				(footprints allowed)
			)
			(placement
				(enabled no)
				(sheetname "")
			)
			(fill
				(thermal_gap 0.5)
				(thermal_bridge_width 0.5)
				(island_removal_mode 0)
			)
			(polygon
				(pts
					(xy 342.011 -19.812) (xy 342.519 -19.812) (xy 342.519 -20.193) (xy 342.011 -20.193)
				)
			)
		)
	)
	(footprint ""
		(layer "F.Cu")
		(at 323.98716 -131.31546)
		(property "Reference" "R6B2"
			(at 0 0 0)
			(layer "F.SilkS")
			(hide yes)
			(effects
				(font
					(size 1.27 1.27)
				)
			)
		)
		(property "Value" ""
			(at 0 0 0)
			(layer "F.Fab")
			(effects
				(font
					(size 1.27 1.27)
				)
			)
		)
		(duplicate_pad_numbers_are_jumpers no)
		(fp_poly
			(pts
				(xy -0.2794 -0.1016) (xy 0.2794 -0.1016) (xy 0.2794 0.9906) (xy -0.2794 0.9906)
			)
			(stroke
				(width 0)
				(type default)
			)
			(fill no)
			(layer "F.CrtYd")
		)
		(fp_line
			(start -0.2794 -0.1016)
			(end -0.2794 0.9906)
			(stroke
				(width 0.1)
				(type default)
			)
			(layer "F.Fab")
		)
		(fp_line
			(start -0.2794 0.9906)
			(end 0.2794 0.9906)
			(stroke
				(width 0.1)
				(type default)
			)
			(layer "F.Fab")
		)
		(fp_line
			(start 0.2794 -0.1016)
			(end -0.2794 -0.1016)
			(stroke
				(width 0.1)
				(type default)
			)
			(layer "F.Fab")
		)
		(fp_line
			(start 0.2794 0.9906)
			(end 0.2794 -0.1016)
			(stroke
				(width 0.1)
				(type default)
			)
			(layer "F.Fab")
		)
		(pad "1" smd rect
			(at 0 0)
			(size 0.508 0.508)
			(layers "F.Cu" "F.Mask" "F.Paste")
			(net "PVCCIO_CPU0")
		)
		(pad "2" smd rect
			(at 0 0.889)
			(size 0.508 0.508)
			(layers "F.Cu" "F.Mask" "F.Paste")
			(net "SVID_DIO1_CPU0_R")
		)
		(zone
			(layer "F.Cu")
			(hatch none 0.5)
			(connect_pads
				(clearance 0)
			)
			(min_thickness 0.25)
			(keepout
				(tracks allowed)
				(vias not_allowed)
				(pads allowed)
				(copperpour not_allowed)
				(footprints allowed)
			)
			(placement
				(enabled no)
				(sheetname "")
			)
			(fill
				(thermal_gap 0.5)
				(thermal_bridge_width 0.5)
				(island_removal_mode 0)
			)
			(polygon
				(pts
					(xy 323.73316 -131.06146) (xy 324.24116 -131.06146) (xy 324.24116 -130.68046) (xy 323.73316 -130.68046)
				)
			)
		)
		(zone
			(layer "F.Cu")
			(hatch none 0.5)
			(connect_pads
				(clearance 0)
			)
			(min_thickness 0.25)
			(keepout
				(tracks not_allowed)
				(vias allowed)
				(pads allowed)
				(copperpour not_allowed)
				(footprints allowed)
			)
			(placement
				(enabled no)
				(sheetname "")
			)
			(fill
				(thermal_gap 0.5)
				(thermal_bridge_width 0.5)
				(island_removal_mode 0)
			)
			(polygon
				(pts
					(xy 323.73316 -130.68046) (xy 324.24116 -130.68046) (xy 324.24116 -131.06146) (xy 323.73316 -131.06146)
				)
			)
		)
	)
	(footprint ""
		(layer "F.Cu")
		(at 394.8176 -66.6242)
		(property "Reference" "C8E15"
			(at 0 0 0)
			(layer "F.SilkS")
			(hide yes)
			(effects
				(font
					(size 1.27 1.27)
				)
			)
		)
		(property "Value" ""
			(at 0 0 0)
			(layer "F.Fab")
			(effects
				(font
					(size 1.27 1.27)
				)
			)
		)
		(duplicate_pad_numbers_are_jumpers no)
		(fp_poly
			(pts
				(xy 0.3048 -0.1016) (xy 0.3048 0.9906) (xy -0.3048 0.9906) (xy -0.3048 -0.1016)
			)
			(stroke
				(width 0)
				(type default)
			)
			(fill no)
			(layer "F.CrtYd")
		)
		(fp_line
			(start -0.3048 -0.1016)
			(end -0.3048 0.9906)
			(stroke
				(width 0.1)
				(type default)
			)
			(layer "F.Fab")
		)
		(fp_line
			(start -0.3048 0.9906)
			(end 0.3048 0.9906)
			(stroke
				(width 0.1)
				(type default)
			)
			(layer "F.Fab")
		)
		(fp_line
			(start 0.3048 -0.1016)
			(end -0.3048 -0.1016)
			(stroke
				(width 0.1)
				(type default)
			)
			(layer "F.Fab")
		)
		(fp_line
			(start 0.3048 0.9906)
			(end 0.3048 -0.1016)
			(stroke
				(width 0.1)
				(type default)
			)
			(layer "F.Fab")
		)
		(pad "1" smd rect
			(at 0 0)
			(size 0.508 0.508)
			(layers "F.Cu" "F.Mask" "F.Paste")
			(net "VR_P5V_STBY_SS")
		)
		(pad "2" smd rect
			(at 0 0.889)
			(size 0.508 0.508)
			(layers "F.Cu" "F.Mask" "F.Paste")
			(net "AGND_P5V_STBY")
		)
		(zone
			(layer "F.Cu")
			(hatch none 0.5)
			(connect_pads
				(clearance 0)
			)
			(min_thickness 0.25)
			(keepout
				(tracks allowed)
				(vias not_allowed)
				(pads allowed)
				(copperpour not_allowed)
				(footprints allowed)
			)
			(placement
				(enabled no)
				(sheetname "")
			)
			(fill
				(thermal_gap 0.5)
				(thermal_bridge_width 0.5)
				(island_removal_mode 0)
			)
			(polygon
				(pts
					(xy 394.5636 -66.3702) (xy 395.0716 -66.3702) (xy 395.0716 -65.9892) (xy 394.5636 -65.9892)
				)
			)
		)
		(zone
			(layer "F.Cu")
			(hatch none 0.5)
			(connect_pads
				(clearance 0)
			)
			(min_thickness 0.25)
			(keepout
				(tracks not_allowed)
				(vias allowed)
				(pads allowed)
				(copperpour not_allowed)
				(footprints allowed)
			)
			(placement
				(enabled no)
				(sheetname "")
			)
			(fill
				(thermal_gap 0.5)
				(thermal_bridge_width 0.5)
				(island_removal_mode 0)
			)
			(polygon
				(pts
					(xy 394.5636 -65.9892) (xy 395.0716 -65.9892) (xy 395.0716 -66.3702) (xy 394.5636 -66.3702)
				)
			)
		)
	)
	(footprint ""
		(layer "F.Cu")
		(at 19.177 13.2715 -90)
		(property "Reference" "T1P33"
			(at 0 0 270)
			(layer "F.SilkS")
			(hide yes)
			(effects
				(font
					(size 1.27 1.27)
				)
			)
		)
		(property "Value" "*"
			(at 0 -3.44805 270)
			(unlocked yes)
			(layer "F.Fab")
			(hide yes)
			(effects
				(font
					(size 0.889 0.889)
					(thickness 0.1524)
				)
			)
		)
		(property "Device Type" "TPAD-SE-2P-GP_DISCRET-GA1-TPADA"
			(at 0 -4.97205 270)
			(unlocked yes)
			(layer "F.Fab")
			(hide yes)
			(effects
				(font
					(size 0.889 0.889)
					(thickness 0.1524)
				)
			)
		)
		(duplicate_pad_numbers_are_jumpers no)
		(fp_line
			(start -1.016 2.286)
			(end -1.016 -2.286)
			(stroke
				(width 0.1524)
				(type default)
			)
			(layer "F.SilkS")
		)
		(fp_line
			(start 1.016 2.286)
			(end -1.016 2.286)
			(stroke
				(width 0.1524)
				(type default)
			)
			(layer "F.SilkS")
		)
		(fp_line
			(start -1.016 -2.286)
			(end 1.016 -2.286)
			(stroke
				(width 0.1524)
				(type default)
			)
			(layer "F.SilkS")
		)
		(fp_line
			(start 1.016 -2.286)
			(end 1.016 2.286)
			(stroke
				(width 0.1524)
				(type default)
			)
			(layer "F.SilkS")
		)
		(fp_rect
			(start -1.27 2.54)
			(end 1.27 -2.54)
			(stroke
				(width 0)
				(type default)
			)
			(fill no)
			(layer "F.CrtYd")
		)
		(fp_rect
			(start -1.27 2.54)
			(end 1.27 -2.54)
			(stroke
				(width 0)
				(type default)
			)
			(fill no)
			(layer "F.Fab")
		)
		(pad "1" thru_hole circle
			(at 0 -1.27 270)
			(size 1.524 1.524)
			(drill 0.9144)
			(layers "*.Cu" "*.Mask")
			(remove_unused_layers no)
			(net "L5_50OHM_6INCH")
			(clearance -0.0508)
			(thermal_gap 0.127)
			(padstack
				(mode front_inner_back)
				(layer "Inner"
					(shape circle)
					(size 1.1684 1.1684)
					(clearance 0.127)
				)
				(layer "B.Cu"
					(shape circle)
					(size 1.524 1.524)
					(clearance -0.0508)
				)
			)
		)
		(pad "GND1" thru_hole rect
			(at 0 1.27 270)
			(size 1.524 1.524)
			(drill 0.9144)
			(layers "*.Cu" "*.Mask")
			(remove_unused_layers no)
			(net "GND")
			(clearance -0.0508)
			(thermal_gap 0.127)
			(padstack
				(mode front_inner_back)
				(layer "Inner"
					(shape circle)
					(size 1.1684 1.1684)
					(clearance 0.127)
				)
				(layer "B.Cu"
					(shape rect)
					(size 1.524 1.524)
					(clearance -0.0508)
				)
			)
		)
	)
	(footprint ""
		(layer "F.Cu")
		(at 24.518112 -98.003868 180)
		(property "Reference" "CF12"
			(at 0 0 180)
			(layer "F.SilkS")
			(hide yes)
			(effects
				(font
					(size 1.27 1.27)
				)
			)
		)
		(property "Value" "*"
			(at 1.1811 -2.8194 180)
			(unlocked yes)
			(layer "F.Fab")
			(hide yes)
			(effects
				(font
					(size 1.27 1.016)
					(thickness 0.1524)
				)
			)
		)
		(property "Device Type" "SC22P50V2JN-4GP_SMD-BCG-SC22P5A"
			(at 1.1811 -4.3434 180)
			(unlocked yes)
			(layer "F.Fab")
			(hide yes)
			(effects
				(font
					(size 1.27 1.016)
					(thickness 0.1524)
				)
			)
		)
		(duplicate_pad_numbers_are_jumpers no)
		(fp_rect
			(start -0.4318 0.9525)
			(end 0.4318 -0.9525)
			(stroke
				(width 0)
				(type default)
			)
			(fill no)
			(layer "F.CrtYd")
		)
		(fp_rect
			(start -0.4318 0.9525)
			(end 0.4318 -0.9525)
			(stroke
				(width 0)
				(type default)
			)
			(fill no)
			(layer "F.Fab")
		)
		(pad "1" smd custom
			(at 0 -0.4445 180)
			(size 0.1524 0.1524)
			(layers "F.Cu" "F.Mask" "F.Paste")
			(net "VR_PVSA_CPU1_BIREF1")
			(options
				(clearance outline)
				(anchor circle)
			)
			(primitives
				(gr_poly
					(pts
						(arc
							(start 0.3048 -0.2032)
							(mid 0.275042 -0.275042)
							(end 0.2032 -0.3048)
						)
						(arc
							(start -0.2032 -0.3048)
							(mid -0.275042 -0.275042)
							(end -0.3048 -0.2032)
						)
						(arc
							(start -0.3048 0.2032)
							(mid -0.275042 0.275042)
							(end -0.2032 0.3048)
						)
						(arc
							(start 0.2032 0.3048)
							(mid 0.275042 0.275042)
							(end 0.3048 0.2032)
						)
					)
					(width 0)
					(fill yes)
				)
			)
		)
		(pad "2" smd custom
			(at 0 0.4445 180)
			(size 0.1524 0.1524)
			(layers "F.Cu" "F.Mask" "F.Paste")
			(net "ISENSE_PVSA_CPU1_IMON")
			(options
				(clearance outline)
				(anchor circle)
			)
			(primitives
				(gr_poly
					(pts
						(arc
							(start 0.3048 -0.2032)
							(mid 0.275042 -0.275042)
							(end 0.2032 -0.3048)
						)
						(arc
							(start -0.2032 -0.3048)
							(mid -0.275042 -0.275042)
							(end -0.3048 -0.2032)
						)
						(arc
							(start -0.3048 0.2032)
							(mid -0.275042 0.275042)
							(end -0.2032 0.3048)
						)
						(arc
							(start 0.2032 0.3048)
							(mid 0.275042 0.275042)
							(end 0.3048 0.2032)
						)
					)
					(width 0)
					(fill yes)
				)
			)
		)
	)
	(footprint ""
		(layer "F.Cu")
		(at 173.507146 -145.667222 90)
		(property "Reference" "C4A14"
			(at 0 0 90)
			(layer "F.SilkS")
			(hide yes)
			(effects
				(font
					(size 1.27 1.27)
				)
			)
		)
		(property "Value" ""
			(at 0 0 90)
			(layer "F.Fab")
			(effects
				(font
					(size 1.27 1.27)
				)
			)
		)
		(duplicate_pad_numbers_are_jumpers no)
		(fp_rect
			(start 0.3048 0.9906)
			(end -0.3048 -0.1016)
			(stroke
				(width 0)
				(type default)
			)
			(fill no)
			(layer "F.CrtYd")
		)
		(fp_line
			(start 0.3048 -0.1016)
			(end -0.3048 -0.1016)
			(stroke
				(width 0.1)
				(type default)
			)
			(layer "F.Fab")
		)
		(fp_line
			(start -0.3048 -0.1016)
			(end -0.3048 0.9906)
			(stroke
				(width 0.1)
				(type default)
			)
			(layer "F.Fab")
		)
		(fp_line
			(start 0.3048 0.9906)
			(end 0.3048 -0.1016)
			(stroke
				(width 0.1)
				(type default)
			)
			(layer "F.Fab")
		)
		(fp_line
			(start -0.3048 0.9906)
			(end 0.3048 0.9906)
			(stroke
				(width 0.1)
				(type default)
			)
			(layer "F.Fab")
		)
		(pad "1" smd rect
			(at 0 0 90)
			(size 0.508 0.508)
			(layers "F.Cu" "F.Mask" "F.Paste")
			(net "VR_PVTT_KLM_VREF")
		)
		(pad "2" smd rect
			(at 0 0.889 90)
			(size 0.508 0.508)
			(layers "F.Cu" "F.Mask" "F.Paste")
			(net "GND")
		)
		(zone
			(layer "F.Cu")
			(hatch none 0.5)
			(connect_pads
				(clearance 0)
			)
			(min_thickness 0.25)
			(keepout
				(tracks allowed)
				(vias not_allowed)
				(pads allowed)
				(copperpour not_allowed)
				(footprints allowed)
			)
			(placement
				(enabled no)
				(sheetname "")
			)
			(fill
				(thermal_gap 0.5)
				(thermal_bridge_width 0.5)
				(island_removal_mode 0)
			)
			(polygon
				(pts
					(xy 174.142146 -145.921222) (xy 173.761146 -145.921222) (xy 173.761146 -145.413222) (xy 174.142146 -145.413222)
				)
			)
		)
		(zone
			(layer "F.Cu")
			(hatch none 0.5)
			(connect_pads
				(clearance 0)
			)
			(min_thickness 0.25)
			(keepout
				(tracks not_allowed)
				(vias allowed)
				(pads allowed)
				(copperpour not_allowed)
				(footprints allowed)
			)
			(placement
				(enabled no)
				(sheetname "")
			)
			(fill
				(thermal_gap 0.5)
				(thermal_bridge_width 0.5)
				(island_removal_mode 0)
			)
			(polygon
				(pts
					(xy 174.142146 -145.921222) (xy 173.761146 -145.921222) (xy 173.761146 -145.413222) (xy 174.142146 -145.413222)
				)
			)
		)
	)
	(footprint ""
		(layer "F.Cu")
		(at 339.3948 -102.6922 90)
		(property "Reference" "C7C10"
			(at 0 0 90)
			(layer "F.SilkS")
			(hide yes)
			(effects
				(font
					(size 1.27 1.27)
				)
			)
		)
		(property "Value" ""
			(at 0 0 90)
			(layer "F.Fab")
			(effects
				(font
					(size 1.27 1.27)
				)
			)
		)
		(duplicate_pad_numbers_are_jumpers no)
		(fp_poly
			(pts
				(xy -0.4953 -0.2032) (xy 0.4953 -0.2032) (xy 0.4953 1.6002) (xy -0.4953 1.6002)
			)
			(stroke
				(width 0)
				(type default)
			)
			(fill no)
			(layer "F.CrtYd")
		)
		(fp_line
			(start 0.4953 -0.2032)
			(end 0.4953 1.6002)
			(stroke
				(width 0.1)
				(type default)
			)
			(layer "F.Fab")
		)
		(fp_line
			(start -0.4953 -0.2032)
			(end 0.4953 -0.2032)
			(stroke
				(width 0.1)
				(type default)
			)
			(layer "F.Fab")
		)
		(fp_line
			(start 0.4953 1.6002)
			(end -0.4953 1.6002)
			(stroke
				(width 0.1)
				(type default)
			)
			(layer "F.Fab")
		)
		(fp_line
			(start -0.4953 1.6002)
			(end -0.4953 -0.2032)
			(stroke
				(width 0.1)
				(type default)
			)
			(layer "F.Fab")
		)
		(pad "1" smd rect
			(at 0 0 90)
			(size 0.762 0.889)
			(layers "F.Cu" "F.Mask" "F.Paste")
			(net "PVCCIO_CPU0")
		)
		(pad "2" smd rect
			(at 0 1.397 90)
			(size 0.762 0.889)
			(layers "F.Cu" "F.Mask" "F.Paste")
			(net "GND")
		)
		(zone
			(layer "F.Cu")
			(hatch none 0.5)
			(connect_pads
				(clearance 0)
			)
			(min_thickness 0.25)
			(keepout
				(tracks not_allowed)
				(vias allowed)
				(pads allowed)
				(copperpour not_allowed)
				(footprints allowed)
			)
			(placement
				(enabled no)
				(sheetname "")
			)
			(fill
				(thermal_gap 0.5)
				(thermal_bridge_width 0.5)
				(island_removal_mode 0)
			)
			(polygon
				(pts
					(xy 339.8393 -102.3112) (xy 339.8393 -103.0732) (xy 340.3473 -103.0732) (xy 340.3473 -102.3112)
				)
			)
		)
	)
)
